(kicad_pcb
	(version 20260206)
	(generator "pcbnew")
	(generator_version "10.0")
	(general
		(thickness 1.6)
		(legacy_teardrops no)
	)
	(paper "A4")
	(title_block
		(title "dpb — 14545-sa.0730WZS0815.brd")
		(comment 1 "Honey Badger (Wiwynn) / footprints 393-396 of 1066")
	)
	(layers
		(0 "F.Cu" signal "TOP")
		(4 "In1.Cu" signal "L2GND")
		(6 "In2.Cu" signal "L3")
		(8 "In3.Cu" signal "L4VCC")
		(10 "In4.Cu" signal "L5VCC")
		(12 "In5.Cu" signal "L6")
		(14 "In6.Cu" signal "L7GND")
		(2 "B.Cu" signal "BOTTOM")
		(9 "F.Adhes" user "F.Adhesive")
		(11 "B.Adhes" user "B.Adhesive")
		(13 "F.Paste" user "Package Geometry/Pastemask Top")
		(15 "B.Paste" user "Package Geometry/Pastemask Bottom")
		(5 "F.SilkS" user "Ref Des/Silkscreen Top")
		(7 "B.SilkS" user "Ref Des/Silkscreen Bottom")
		(1 "F.Mask" user "Board Geometry/Soldermask Top")
		(3 "B.Mask" user "Board Geometry/Soldermask Bottom")
		(17 "Dwgs.User" user "User.Drawings")
		(19 "Cmts.User" user "User.Comments")
		(21 "Eco1.User" user "User.Eco1")
		(23 "Eco2.User" user "User.Eco2")
		(25 "Edge.Cuts" user "Board Geometry/Outline")
		(27 "Margin" user)
		(31 "F.CrtYd" user "Package Geometry/Place Bound Top")
		(29 "B.CrtYd" user "Package Geometry/Place Bound Bottom")
		(35 "F.Fab" user "Ref Des/Assembly Top")
		(33 "B.Fab" user "Ref Des/Assembly Bottom")
	)
	(footprint ""
		(layer "F.Cu")
		(at 33.273746 -269.2527 -90)
		(property "Reference" "C216"
			(at 0 0 270)
			(layer "F.SilkS")
			(hide yes)
			(effects
				(font
					(size 1.27 1.27)
				)
			)
		)
		(property "Value" "SCD01U50V2KX-1GP"
			(at 1.1811 -2.7051 270)
			(unlocked yes)
			(layer "F.Fab")
			(hide yes)
			(effects
				(font
					(size 1.016 1.016)
					(thickness 0.1524)
				)
			)
		)
		(property "Device Type" "C402H22"
			(at 1.1811 -4.2291 270)
			(unlocked yes)
			(layer "F.Fab")
			(hide yes)
			(effects
				(font
					(size 1.016 1.016)
					(thickness 0.1524)
				)
			)
		)
		(duplicate_pad_numbers_are_jumpers no)
		(fp_rect
			(start -0.4318 0.9525)
			(end 0.4318 -0.9525)
			(stroke
				(width 0)
				(type default)
			)
			(fill no)
			(layer "F.CrtYd")
		)
		(fp_rect
			(start -0.4318 0.9525)
			(end 0.4318 -0.9525)
			(stroke
				(width 0)
				(type default)
			)
			(fill no)
			(layer "F.Fab")
		)
		(pad "1" smd custom
			(at 0 -0.4445 270)
			(size 0.1524 0.1524)
			(layers "F.Cu" "F.Mask" "F.Paste")
			(net "SAS2X28_DRIVE_RX_N_B7")
			(options
				(clearance outline)
				(anchor circle)
			)
			(primitives
				(gr_poly
					(pts
						(arc
							(start 0.3048 -0.2032)
							(mid 0.275042 -0.275042)
							(end 0.2032 -0.3048)
						)
						(arc
							(start -0.2032 -0.3048)
							(mid -0.275042 -0.275042)
							(end -0.3048 -0.2032)
						)
						(arc
							(start -0.3048 0.2032)
							(mid -0.275042 0.275042)
							(end -0.2032 0.3048)
						)
						(arc
							(start 0.2032 0.3048)
							(mid 0.275042 0.275042)
							(end 0.3048 0.2032)
						)
					)
					(width 0)
					(fill yes)
				)
			)
		)
		(pad "2" smd custom
			(at 0 0.4445 270)
			(size 0.1524 0.1524)
			(layers "F.Cu" "F.Mask" "F.Paste")
			(net "SAS2X28_B_HDD7_RX_-")
			(options
				(clearance outline)
				(anchor circle)
			)
			(primitives
				(gr_poly
					(pts
						(arc
							(start 0.3048 -0.2032)
							(mid 0.275042 -0.275042)
							(end 0.2032 -0.3048)
						)
						(arc
							(start -0.2032 -0.3048)
							(mid -0.275042 -0.275042)
							(end -0.3048 -0.2032)
						)
						(arc
							(start -0.3048 0.2032)
							(mid -0.275042 0.275042)
							(end -0.2032 0.3048)
						)
						(arc
							(start 0.2032 0.3048)
							(mid 0.275042 0.275042)
							(end 0.3048 0.2032)
						)
					)
					(width 0)
					(fill yes)
				)
			)
		)
	)
	(footprint ""
		(layer "F.Cu")
		(at 26.542746 -322.735702)
		(property "Reference" "C284"
			(at 0 0 0)
			(layer "F.SilkS")
			(hide yes)
			(effects
				(font
					(size 1.27 1.27)
				)
			)
		)
		(property "Value" "SC1U16V3KX-5GP"
			(at 0 -2.8194 0)
			(unlocked yes)
			(layer "F.Fab")
			(hide yes)
			(effects
				(font
					(size 1.016 1.016)
					(thickness 0.1524)
				)
			)
		)
		(property "Device Type" "C603H36"
			(at 0 -4.3434 0)
			(unlocked yes)
			(layer "F.Fab")
			(hide yes)
			(effects
				(font
					(size 1.016 1.016)
					(thickness 0.1524)
				)
			)
		)
		(duplicate_pad_numbers_are_jumpers no)
		(fp_line
			(start 0.508 0)
			(end -0.508 0)
			(stroke
				(width 0.2032)
				(type default)
			)
			(layer "F.SilkS")
		)
		(fp_rect
			(start -0.5842 1.3335)
			(end 0.5842 -1.3335)
			(stroke
				(width 0)
				(type default)
			)
			(fill no)
			(layer "F.CrtYd")
		)
		(fp_rect
			(start -0.5842 1.3335)
			(end 0.5842 -1.3335)
			(stroke
				(width 0)
				(type default)
			)
			(fill no)
			(layer "F.Fab")
		)
		(pad "1" smd custom
			(at 0 -0.762)
			(size 0.2159 0.2159)
			(layers "F.Cu" "F.Mask" "F.Paste")
			(net "P5V_HDD11")
			(options
				(clearance outline)
				(anchor circle)
			)
			(primitives
				(gr_poly
					(pts
						(arc
							(start -0.3302 -0.4318)
							(mid -0.402042 -0.402042)
							(end -0.4318 -0.3302)
						)
						(arc
							(start -0.4318 0.3302)
							(mid -0.402042 0.402042)
							(end -0.3302 0.4318)
						)
						(arc
							(start 0.3302 0.4318)
							(mid 0.402042 0.402042)
							(end 0.4318 0.3302)
						)
						(arc
							(start 0.4318 -0.3302)
							(mid 0.402042 -0.402042)
							(end 0.3302 -0.4318)
						)
					)
					(width 0)
					(fill yes)
				)
			)
		)
		(pad "2" smd custom
			(at 0 0.762)
			(size 0.2159 0.2159)
			(layers "F.Cu" "F.Mask" "F.Paste")
			(net "GND")
			(options
				(clearance outline)
				(anchor circle)
			)
			(primitives
				(gr_poly
					(pts
						(arc
							(start -0.3302 -0.4318)
							(mid -0.402042 -0.402042)
							(end -0.4318 -0.3302)
						)
						(arc
							(start -0.4318 0.3302)
							(mid -0.402042 0.402042)
							(end -0.3302 0.4318)
						)
						(arc
							(start 0.3302 0.4318)
							(mid 0.402042 0.402042)
							(end 0.4318 0.3302)
						)
						(arc
							(start 0.4318 -0.3302)
							(mid 0.402042 -0.402042)
							(end 0.3302 -0.4318)
						)
					)
					(width 0)
					(fill yes)
				)
			)
		)
	)
	(footprint ""
		(layer "F.Cu")
		(at 56.209946 -191.7827 180)
		(property "Reference" "C242"
			(at 0 0 180)
			(layer "F.SilkS")
			(hide yes)
			(effects
				(font
					(size 1.27 1.27)
				)
			)
		)
		(property "Value" "SC10U25V6KX-1GP"
			(at -0.0762 -5.1308 180)
			(unlocked yes)
			(layer "F.Fab")
			(hide yes)
			(effects
				(font
					(size 1.016 1.016)
					(thickness 0.1524)
				)
			)
		)
		(property "Device Type" "C1206H71"
			(at -0.127 -6.6548 180)
			(unlocked yes)
			(layer "F.Fab")
			(hide yes)
			(effects
				(font
					(size 1.016 1.016)
					(thickness 0.1524)
				)
			)
		)
		(duplicate_pad_numbers_are_jumpers no)
		(fp_line
			(start 1.016 2.2352)
			(end -1.016 2.2352)
			(stroke
				(width 0.1524)
				(type default)
			)
			(layer "F.SilkS")
		)
		(fp_line
			(start 1.016 0.8382)
			(end 1.016 2.2352)
			(stroke
				(width 0.1524)
				(type default)
			)
			(layer "F.SilkS")
		)
		(fp_line
			(start 1.016 -2.2352)
			(end 1.016 -0.8382)
			(stroke
				(width 0.1524)
				(type default)
			)
			(layer "F.SilkS")
		)
		(fp_line
			(start -1.016 2.2352)
			(end -1.016 0.8382)
			(stroke
				(width 0.1524)
				(type default)
			)
			(layer "F.SilkS")
		)
		(fp_line
			(start -1.016 -0.8382)
			(end -1.016 -2.2352)
			(stroke
				(width 0.1524)
				(type default)
			)
			(layer "F.SilkS")
		)
		(fp_line
			(start -1.016 -2.2352)
			(end 1.016 -2.2352)
			(stroke
				(width 0.1524)
				(type default)
			)
			(layer "F.SilkS")
		)
		(fp_rect
			(start -1.0922 2.3114)
			(end 1.0922 -2.3114)
			(stroke
				(width 0)
				(type default)
			)
			(fill no)
			(layer "F.CrtYd")
		)
		(fp_poly
			(pts
				(xy 1.0922 -2.3114) (xy 1.0922 2.3114) (xy -1.0922 2.3114) (xy -1.0922 -2.3114)
			)
			(stroke
				(width 0)
				(type default)
			)
			(fill no)
			(layer "F.Fab")
		)
		(pad "1" smd rect
			(at 0 -1.397 180)
			(size 1.651 1.27)
			(layers "F.Cu" "F.Mask" "F.Paste")
			(net "P12V_HDD8")
		)
		(pad "2" smd rect
			(at 0 1.397 180)
			(size 1.651 1.27)
			(layers "F.Cu" "F.Mask" "F.Paste")
			(net "GND")
		)
	)
	(footprint ""
		(layer "F.Cu")
		(at 218.646756 -476.151702 -90)
		(property "Reference" "C105"
			(at 0 0 270)
			(layer "F.SilkS")
			(hide yes)
			(effects
				(font
					(size 1.27 1.27)
				)
			)
		)
		(property "Value" "SCD01U50V2KX-1GP"
			(at 1.1811 -2.7051 270)
			(unlocked yes)
			(layer "F.Fab")
			(hide yes)
			(effects
				(font
					(size 1.016 1.016)
					(thickness 0.1524)
				)
			)
		)
		(property "Device Type" "C402H22"
			(at 1.1811 -4.2291 270)
			(unlocked yes)
			(layer "F.Fab")
			(hide yes)
			(effects
				(font
					(size 1.016 1.016)
					(thickness 0.1524)
				)
			)
		)
		(duplicate_pad_numbers_are_jumpers no)
		(fp_rect
			(start -0.4318 0.9525)
			(end 0.4318 -0.9525)
			(stroke
				(width 0)
				(type default)
			)
			(fill no)
			(layer "F.CrtYd")
		)
		(fp_rect
			(start -0.4318 0.9525)
			(end 0.4318 -0.9525)
			(stroke
				(width 0)
				(type default)
			)
			(fill no)
			(layer "F.Fab")
		)
		(pad "1" smd custom
			(at 0 -0.4445 270)
			(size 0.1524 0.1524)
			(layers "F.Cu" "F.Mask" "F.Paste")
			(net "SAS2X28_DRIVE_RX_P_B0")
			(options
				(clearance outline)
				(anchor circle)
			)
			(primitives
				(gr_poly
					(pts
						(arc
							(start 0.3048 -0.2032)
							(mid 0.275042 -0.275042)
							(end 0.2032 -0.3048)
						)
						(arc
							(start -0.2032 -0.3048)
							(mid -0.275042 -0.275042)
							(end -0.3048 -0.2032)
						)
						(arc
							(start -0.3048 0.2032)
							(mid -0.275042 0.275042)
							(end -0.2032 0.3048)
						)
						(arc
							(start 0.2032 0.3048)
							(mid 0.275042 0.275042)
							(end 0.3048 0.2032)
						)
					)
					(width 0)
					(fill yes)
				)
			)
		)
		(pad "2" smd custom
			(at 0 0.4445 270)
			(size 0.1524 0.1524)
			(layers "F.Cu" "F.Mask" "F.Paste")
			(net "SAS2X28_B_HDD0_RX_+")
			(options
				(clearance outline)
				(anchor circle)
			)
			(primitives
				(gr_poly
					(pts
						(arc
							(start 0.3048 -0.2032)
							(mid 0.275042 -0.275042)
							(end 0.2032 -0.3048)
						)
						(arc
							(start -0.2032 -0.3048)
							(mid -0.275042 -0.275042)
							(end -0.3048 -0.2032)
						)
						(arc
							(start -0.3048 0.2032)
							(mid -0.275042 0.275042)
							(end -0.2032 0.3048)
						)
						(arc
							(start 0.2032 0.3048)
							(mid 0.275042 0.275042)
							(end 0.3048 0.2032)
						)
					)
					(width 0)
					(fill yes)
				)
			)
		)
	)
)
